# S9S_MB_2U (Grand Teton) — schematic netlist excerpt (pin names and nets, part order shuffled) for the footprints in the layout excerpt that follows; sources: Cadence DE-HDL packaged netlist, KiCad conversion of 03242023_DA0F0TMBIJ0_F0T_Motherboard_J_brd_V01_OCP.brd

R3084  Q_RES  130 1% CHIP  pkg 0402LF  page 256 : A = LED_RST_PLD_CPU1_DRAM_CD_N ; B = P3V3_AUX
H20  HOLE  EMPTY  pkg TH  page 311 : \1\ = NC
C829  Q_CAP_DIFFBUS  DIFF BUS_0.22UF 6.3V 20% X6S  pkg C0201  page 175 : \1\ = P5E_CPU1_PE1_TX_C_DP<4> ; \2\ = P5E_CPU1_PE1_TX_DP<4>

(kicad_pcb
	(version 20260206)
	(generator "pcbnew")
	(generator_version "10.0")
	(general
		(thickness 1.6)
		(legacy_teardrops no)
	)
	(paper "A4")
	(title_block
		(title "03242023_DA0F0TMBIJ0_F0T_Motherboard_J_brd_V01_OCP.brd")
		(comment 1 "Grand Teton / footprints 3992-3994 of 6105")
	)
	(layers
		(0 "F.Cu" signal "TOP")
		(4 "In1.Cu" signal "GND")
		(6 "In2.Cu" signal "IN1")
		(8 "In3.Cu" signal "GND1")
		(10 "In4.Cu" signal "IN2")
		(12 "In5.Cu" signal "GND2")
		(14 "In6.Cu" signal "IN3")
		(16 "In7.Cu" signal "GND3")
		(18 "In8.Cu" signal "VCC")
		(20 "In9.Cu" signal "VCC1")
		(22 "In10.Cu" signal "GND4")
		(24 "In11.Cu" signal "IN4")
		(26 "In12.Cu" signal "GND5")
		(28 "In13.Cu" signal "IN5")
		(30 "In14.Cu" signal "GND6")
		(32 "In15.Cu" signal "IN6")
		(34 "In16.Cu" signal "GND7")
		(2 "B.Cu" signal "BOTTOM")
		(9 "F.Adhes" user "F.Adhesive")
		(11 "B.Adhes" user "B.Adhesive")
		(13 "F.Paste" user "Package Geometry/Pastemask Top")
		(15 "B.Paste" user "Package Geometry/Pastemask Bottom")
		(5 "F.SilkS" user "Ref Des/Silkscreen Top")
		(7 "B.SilkS" user "Ref Des/Silkscreen Bottom")
		(1 "F.Mask" user "Board Geometry/Soldermask Top")
		(3 "B.Mask" user "Board Geometry/Soldermask Bottom")
		(17 "Dwgs.User" user "User.Drawings")
		(19 "Cmts.User" user "User.Comments")
		(21 "Eco1.User" user "User.Eco1")
		(23 "Eco2.User" user "User.Eco2")
		(25 "Edge.Cuts" user "Board Geometry/Outline")
		(27 "Margin" user)
		(31 "F.CrtYd" user "Package Geometry/Place Bound Top")
		(29 "B.CrtYd" user "Package Geometry/Place Bound Bottom")
		(35 "F.Fab" user "Ref Des/Assembly Top")
		(33 "B.Fab" user "Ref Des/Assembly Bottom")
	)
	(footprint ""
		(layer "F.Cu")
		(at 70.228714 -65.082674 -90)
		(property "Reference" "R3084"
			(at 0 0 270)
			(layer "F.SilkS")
			(hide yes)
			(effects
				(font
					(size 1.27 1.27)
				)
			)
		)
		(property "Value" ""
			(at 0 0 270)
			(layer "F.Fab")
			(effects
				(font
					(size 1.27 1.27)
				)
			)
		)
		(duplicate_pad_numbers_are_jumpers no)
		(fp_line
			(start -0.7874 0.4064)
			(end -0.7874 -0.4064)
			(stroke
				(width 0.1524)
				(type default)
			)
			(layer "F.SilkS")
		)
		(fp_line
			(start 0.7874 0.4064)
			(end -0.7874 0.4064)
			(stroke
				(width 0.1524)
				(type default)
			)
			(layer "F.SilkS")
		)
		(fp_line
			(start -0.7874 -0.4064)
			(end 0.7874 -0.4064)
			(stroke
				(width 0.1524)
				(type default)
			)
			(layer "F.SilkS")
		)
		(fp_line
			(start 0.7874 -0.4064)
			(end 0.7874 0.4064)
			(stroke
				(width 0.1524)
				(type default)
			)
			(layer "F.SilkS")
		)
		(fp_line
			(start -0.67945 0.3048)
			(end -0.67945 -0.305054)
			(stroke
				(width 0.1)
				(type default)
			)
			(layer "F.Fab")
		)
		(fp_line
			(start -0.12065 0.3048)
			(end -0.67945 0.3048)
			(stroke
				(width 0.1)
				(type default)
			)
			(layer "F.Fab")
		)
		(fp_line
			(start 0.120396 0.3048)
			(end 0.120396 0.2794)
			(stroke
				(width 0.1)
				(type default)
			)
			(layer "F.Fab")
		)
		(fp_line
			(start 0.67945 0.3048)
			(end 0.120396 0.3048)
			(stroke
				(width 0.1)
				(type default)
			)
			(layer "F.Fab")
		)
		(fp_line
			(start -0.12065 0.2794)
			(end -0.12065 0.3048)
			(stroke
				(width 0.1)
				(type default)
			)
			(layer "F.Fab")
		)
		(fp_line
			(start 0.120396 0.2794)
			(end -0.12065 0.2794)
			(stroke
				(width 0.1)
				(type default)
			)
			(layer "F.Fab")
		)
		(fp_line
			(start -0.12065 -0.2794)
			(end 0.12065 -0.2794)
			(stroke
				(width 0.1)
				(type default)
			)
			(layer "F.Fab")
		)
		(fp_line
			(start 0.12065 -0.2794)
			(end 0.12065 -0.3048)
			(stroke
				(width 0.1)
				(type default)
			)
			(layer "F.Fab")
		)
		(fp_line
			(start 0.12065 -0.3048)
			(end 0.67945 -0.3048)
			(stroke
				(width 0.1)
				(type default)
			)
			(layer "F.Fab")
		)
		(fp_line
			(start 0.67945 -0.3048)
			(end 0.67945 0.3048)
			(stroke
				(width 0.1)
				(type default)
			)
			(layer "F.Fab")
		)
		(fp_line
			(start -0.67945 -0.305054)
			(end -0.12065 -0.305054)
			(stroke
				(width 0.1)
				(type default)
			)
			(layer "F.Fab")
		)
		(fp_line
			(start -0.12065 -0.305054)
			(end -0.12065 -0.2794)
			(stroke
				(width 0.1)
				(type default)
			)
			(layer "F.Fab")
		)
		(pad "1" smd circle
			(at -0.40005 0 270)
			(size 0 0)
			(layers "F.Cu" "F.Mask" "F.Paste")
			(net "LED_RST_PLD_CPU1_DRAM_CD_N")
		)
		(pad "2" smd circle
			(at 0.40005 0 270)
			(size 0 0)
			(layers "F.Cu" "F.Mask" "F.Paste")
			(net "P3V3_AUX")
		)
	)
	(footprint ""
		(layer "F.Cu")
		(at 47.462694 -17.623536 90)
		(property "Reference" "C829"
			(at 0 0 90)
			(layer "F.SilkS")
			(hide yes)
			(effects
				(font
					(size 1.27 1.27)
				)
			)
		)
		(property "Value" ""
			(at 0 0 90)
			(layer "F.Fab")
			(effects
				(font
					(size 1.27 1.27)
				)
			)
		)
		(duplicate_pad_numbers_are_jumpers no)
		(fp_line
			(start 0.299974 -0.150114)
			(end 0.299974 0.150114)
			(stroke
				(width 0.1)
				(type default)
			)
			(layer "F.Fab")
		)
		(fp_line
			(start -0.299974 -0.150114)
			(end 0.299974 -0.150114)
			(stroke
				(width 0.1)
				(type default)
			)
			(layer "F.Fab")
		)
		(fp_line
			(start 0.299974 0.150114)
			(end -0.299974 0.150114)
			(stroke
				(width 0.1)
				(type default)
			)
			(layer "F.Fab")
		)
		(fp_line
			(start -0.299974 0.150114)
			(end -0.299974 -0.150114)
			(stroke
				(width 0.1)
				(type default)
			)
			(layer "F.Fab")
		)
		(pad "1" smd rect
			(at -0.2667 0 90)
			(size 0.3048 0.381)
			(layers "F.Cu" "F.Mask" "F.Paste")
			(net "P5E_CPU1_PE1_TX_C_DP<4>")
		)
		(pad "2" smd rect
			(at 0.2667 0 90)
			(size 0.3048 0.381)
			(layers "F.Cu" "F.Mask" "F.Paste")
			(net "P5E_CPU1_PE1_TX_DP<4>")
		)
	)
	(footprint ""
		(layer "F.Cu")
		(at 88.925146 -206.024734)
		(property "Reference" "H20"
			(at -0.34036 3.860292 0)
			(unlocked yes)
			(layer "F.SilkS")
			(effects
				(font
					(size 0.7874 0.5842)
					(thickness 0.1524)
				)
				(justify left)
			)
		)
		(property "Value" ""
			(at 0 0 0)
			(layer "F.Fab")
			(effects
				(font
					(size 1.27 1.27)
				)
			)
		)
		(duplicate_pad_numbers_are_jumpers no)
		(fp_circle
			(center 0 0)
			(end 2.5273 0)
			(stroke
				(width 0.1524)
				(type default)
			)
			(fill no)
			(layer "F.SilkS")
		)
		(fp_circle
			(center 0 0)
			(end 2.5273 0)
			(stroke
				(width 0.1524)
				(type default)
			)
			(fill no)
			(layer "B.SilkS")
		)
		(fp_circle
			(center 0 0)
			(end 2.5273 0)
			(stroke
				(width 0.1)
				(type default)
			)
			(fill no)
			(layer "B.Fab")
		)
		(fp_circle
			(center 0 0)
			(end 2.5273 0)
			(stroke
				(width 0.1)
				(type default)
			)
			(fill no)
			(layer "F.Fab")
		)
		(pad "" np_thru_hole circle
			(at 0 0)
			(size 3.429 3.429)
			(drill 3.429)
			(layers "*.Cu" "*.Mask")
			(clearance 0.381)
			(thermal_gap 0.381)
		)
	)
)
